# S9S_MB_2U (Grand Teton) — schematic netlist excerpt (pin names and nets, part order shuffled) for the footprints in the layout excerpt that follows; sources: Cadence DE-HDL packaged netlist, KiCad conversion of 03242023_DA0F0TMBIJ0_F0T_Motherboard_J_brd_V01_OCP.brd

Q75  MOSFET_NCH_DUAL  PJT138K IC  pkg SOT363XD  page 148
  S1  = GND
  G1  = FM_SMB_1_ALERT_GPU_N
  D2  = FM_SMB_1_ALERT_GPU_ISO_N
  S2  = GND
  G2  = FM_SMB_1_ALERT_GPU
  D1  = FM_SMB_1_ALERT_GPU

PR1298  Q_RES  8.87K 1% EMPTY  pkg 0402LF  page 272 : A = PVCCFA_EHV_FIVRA_CPU0_LSET3 ; B = GND

(kicad_pcb
	(version 20260206)
	(generator "pcbnew")
	(generator_version "10.0")
	(general
		(thickness 1.6)
		(legacy_teardrops no)
	)
	(paper "A4")
	(title_block
		(title "03242023_DA0F0TMBIJ0_F0T_Motherboard_J_brd_V01_OCP.brd")
		(comment 1 "Grand Teton / footprints 3678-3679 of 6105")
	)
	(layers
		(0 "F.Cu" signal "TOP")
		(4 "In1.Cu" signal "GND")
		(6 "In2.Cu" signal "IN1")
		(8 "In3.Cu" signal "GND1")
		(10 "In4.Cu" signal "IN2")
		(12 "In5.Cu" signal "GND2")
		(14 "In6.Cu" signal "IN3")
		(16 "In7.Cu" signal "GND3")
		(18 "In8.Cu" signal "VCC")
		(20 "In9.Cu" signal "VCC1")
		(22 "In10.Cu" signal "GND4")
		(24 "In11.Cu" signal "IN4")
		(26 "In12.Cu" signal "GND5")
		(28 "In13.Cu" signal "IN5")
		(30 "In14.Cu" signal "GND6")
		(32 "In15.Cu" signal "IN6")
		(34 "In16.Cu" signal "GND7")
		(2 "B.Cu" signal "BOTTOM")
		(9 "F.Adhes" user "F.Adhesive")
		(11 "B.Adhes" user "B.Adhesive")
		(13 "F.Paste" user "Package Geometry/Pastemask Top")
		(15 "B.Paste" user "Package Geometry/Pastemask Bottom")
		(5 "F.SilkS" user "Ref Des/Silkscreen Top")
		(7 "B.SilkS" user "Ref Des/Silkscreen Bottom")
		(1 "F.Mask" user "Board Geometry/Soldermask Top")
		(3 "B.Mask" user "Board Geometry/Soldermask Bottom")
		(17 "Dwgs.User" user "User.Drawings")
		(19 "Cmts.User" user "User.Comments")
		(21 "Eco1.User" user "User.Eco1")
		(23 "Eco2.User" user "User.Eco2")
		(25 "Edge.Cuts" user "Board Geometry/Outline")
		(27 "Margin" user)
		(31 "F.CrtYd" user "Package Geometry/Place Bound Top")
		(29 "B.CrtYd" user "Package Geometry/Place Bound Bottom")
		(35 "F.Fab" user "Ref Des/Assembly Top")
		(33 "B.Fab" user "Ref Des/Assembly Bottom")
	)
	(footprint ""
		(layer "F.Cu")
		(at 116.71808 -397.747998 -90)
		(property "Reference" "Q75"
			(at 0.64516 -1.48082 0)
			(unlocked yes)
			(layer "F.SilkS")
			(effects
				(font
					(size 0.7874 0.5842)
					(thickness 0.1524)
				)
				(justify left)
			)
		)
		(property "Value" ""
			(at 0 0 270)
			(layer "F.Fab")
			(effects
				(font
					(size 1.27 1.27)
				)
			)
		)
		(duplicate_pad_numbers_are_jumpers no)
		(fp_line
			(start -1.332738 1.100074)
			(end -1.332738 -1.100074)
			(stroke
				(width 0.1524)
				(type default)
			)
			(layer "F.SilkS")
		)
		(fp_line
			(start 1.332738 1.100074)
			(end -1.332738 1.100074)
			(stroke
				(width 0.1524)
				(type default)
			)
			(layer "F.SilkS")
		)
		(fp_line
			(start 0 -0.541274)
			(end 0.4826 -1.100074)
			(stroke
				(width 0.1524)
				(type default)
			)
			(layer "F.SilkS")
		)
		(fp_line
			(start -1.332738 -1.100074)
			(end -0.4826 -1.100074)
			(stroke
				(width 0.1524)
				(type default)
			)
			(layer "F.SilkS")
		)
		(fp_line
			(start -0.4826 -1.100074)
			(end 0 -0.541274)
			(stroke
				(width 0.1524)
				(type default)
			)
			(layer "F.SilkS")
		)
		(fp_line
			(start 0.4826 -1.100074)
			(end 1.332738 -1.100074)
			(stroke
				(width 0.1524)
				(type default)
			)
			(layer "F.SilkS")
		)
		(fp_line
			(start 1.332738 -1.100074)
			(end 1.332738 1.100074)
			(stroke
				(width 0.1524)
				(type default)
			)
			(layer "F.SilkS")
		)
		(fp_poly
			(pts
				(xy -0.801116 -2.02311) (xy -1.152144 -1.321054) (xy -1.503172 -2.02311)
			)
			(stroke
				(width 0)
				(type default)
			)
			(fill yes)
			(layer "F.SilkS")
		)
		(fp_line
			(start -0.674878 1.100074)
			(end -0.674878 -1.100074)
			(stroke
				(width 0.1)
				(type default)
			)
			(layer "F.Fab")
		)
		(fp_line
			(start 0.674878 1.100074)
			(end -0.674878 1.100074)
			(stroke
				(width 0.1)
				(type default)
			)
			(layer "F.Fab")
		)
		(fp_line
			(start -0.674878 -1.100074)
			(end 0.674878 -1.100074)
			(stroke
				(width 0.1)
				(type default)
			)
			(layer "F.Fab")
		)
		(fp_line
			(start 0.674878 -1.100074)
			(end 0.674878 1.100074)
			(stroke
				(width 0.1)
				(type default)
			)
			(layer "F.Fab")
		)
		(fp_poly
			(pts
				(xy -2.2352 -0.298958) (xy -2.2352 -1.001014) (xy -1.533144 -0.649986)
			)
			(stroke
				(width 0)
				(type default)
			)
			(fill yes)
			(layer "F.Fab")
		)
		(pad "1" smd rect
			(at -0.94996 -0.649986)
			(size 0.4318 0.508)
			(layers "F.Cu" "F.Mask" "F.Paste")
			(net "GND")
		)
		(pad "2" smd rect
			(at -0.94996 0)
			(size 0.4318 0.508)
			(layers "F.Cu" "F.Mask" "F.Paste")
			(net "FM_SMB_1_ALERT_GPU_N")
		)
		(pad "3" smd rect
			(at -0.94996 0.649986)
			(size 0.4318 0.508)
			(layers "F.Cu" "F.Mask" "F.Paste")
			(net "FM_SMB_1_ALERT_GPU_ISO_N")
		)
		(pad "4" smd rect
			(at 0.94996 0.649986)
			(size 0.4318 0.508)
			(layers "F.Cu" "F.Mask" "F.Paste")
			(net "GND")
		)
		(pad "5" smd rect
			(at 0.94996 0)
			(size 0.4318 0.508)
			(layers "F.Cu" "F.Mask" "F.Paste")
			(net "FM_SMB_1_ALERT_GPU")
		)
		(pad "6" smd rect
			(at 0.94996 -0.649986)
			(size 0.4318 0.508)
			(layers "F.Cu" "F.Mask" "F.Paste")
			(net "FM_SMB_1_ALERT_GPU")
		)
	)
	(footprint ""
		(layer "F.Cu")
		(at 424.557444 -367.231676)
		(property "Reference" "PR1298"
			(at 0 0 0)
			(layer "F.SilkS")
			(hide yes)
			(effects
				(font
					(size 1.27 1.27)
				)
			)
		)
		(property "Value" ""
			(at 0 0 0)
			(layer "F.Fab")
			(effects
				(font
					(size 1.27 1.27)
				)
			)
		)
		(duplicate_pad_numbers_are_jumpers no)
		(fp_line
			(start -0.7874 -0.4064)
			(end 0.7874 -0.4064)
			(stroke
				(width 0.1524)
				(type default)
			)
			(layer "F.SilkS")
		)
		(fp_line
			(start -0.7874 0.4064)
			(end -0.7874 -0.4064)
			(stroke
				(width 0.1524)
				(type default)
			)
			(layer "F.SilkS")
		)
		(fp_line
			(start 0.7874 -0.4064)
			(end 0.7874 0.4064)
			(stroke
				(width 0.1524)
				(type default)
			)
			(layer "F.SilkS")
		)
		(fp_line
			(start 0.7874 0.4064)
			(end -0.7874 0.4064)
			(stroke
				(width 0.1524)
				(type default)
			)
			(layer "F.SilkS")
		)
		(fp_line
			(start -0.67945 -0.305054)
			(end -0.12065 -0.305054)
			(stroke
				(width 0.1)
				(type default)
			)
			(layer "F.Fab")
		)
		(fp_line
			(start -0.67945 0.3048)
			(end -0.67945 -0.305054)
			(stroke
				(width 0.1)
				(type default)
			)
			(layer "F.Fab")
		)
		(fp_line
			(start -0.12065 -0.305054)
			(end -0.12065 -0.2794)
			(stroke
				(width 0.1)
				(type default)
			)
			(layer "F.Fab")
		)
		(fp_line
			(start -0.12065 -0.2794)
			(end 0.12065 -0.2794)
			(stroke
				(width 0.1)
				(type default)
			)
			(layer "F.Fab")
		)
		(fp_line
			(start -0.12065 0.2794)
			(end -0.12065 0.3048)
			(stroke
				(width 0.1)
				(type default)
			)
			(layer "F.Fab")
		)
		(fp_line
			(start -0.12065 0.3048)
			(end -0.67945 0.3048)
			(stroke
				(width 0.1)
				(type default)
			)
			(layer "F.Fab")
		)
		(fp_line
			(start 0.120396 0.2794)
			(end -0.12065 0.2794)
			(stroke
				(width 0.1)
				(type default)
			)
			(layer "F.Fab")
		)
		(fp_line
			(start 0.120396 0.3048)
			(end 0.120396 0.2794)
			(stroke
				(width 0.1)
				(type default)
			)
			(layer "F.Fab")
		)
		(fp_line
			(start 0.12065 -0.3048)
			(end 0.67945 -0.3048)
			(stroke
				(width 0.1)
				(type default)
			)
			(layer "F.Fab")
		)
		(fp_line
			(start 0.12065 -0.2794)
			(end 0.12065 -0.3048)
			(stroke
				(width 0.1)
				(type default)
			)
			(layer "F.Fab")
		)
		(fp_line
			(start 0.67945 -0.3048)
			(end 0.67945 0.3048)
			(stroke
				(width 0.1)
				(type default)
			)
			(layer "F.Fab")
		)
		(fp_line
			(start 0.67945 0.3048)
			(end 0.120396 0.3048)
			(stroke
				(width 0.1)
				(type default)
			)
			(layer "F.Fab")
		)
		(pad "1" smd circle
			(at -0.40005 0)
			(size 0 0)
			(layers "F.Cu" "F.Mask" "F.Paste")
			(net "PVCCFA_EHV_FIVRA_CPU0_LSET3")
		)
		(pad "2" smd circle
			(at 0.40005 0)
			(size 0 0)
			(layers "F.Cu" "F.Mask" "F.Paste")
			(net "GND")
		)
	)
)
